FILE_TYPE = CONNECTIVITY;
{Allegro Design Entry HDL 16.6-p007 (v16-6-112F) 10/10/2012}
"PAGE_NUMBER" = 88;
0"NC";
1"M_M_DQS_DP<17:0>";
2"M_M_DQS_DN<17:0>";
3"M_M_MA<17:0>";
4"M_M_DQ<63:0>";
5"M_M_CLK_DN<3:0>";
6"M_M_CLK_DP<3:0>";
7"M_M_CS_N<7:0>";
8"M_M_CKE<3:0>";
9"M_M_ODT<3:0>";
10"M_M_BA<1:0>";
11"M_M_BG<1:0>";
12"M_M_ECC<7:0>";
13"PVDDQ_KLM\g";
14"GND\g";
15"GND\g";
16"GND\g";
17"PVPP_KLM\g";
18"PVPP_KLM\g";
19"P12V_NVDIMM_KLM\g";
20"GND\g";
21"PVTT_KLM\g";
22"M_M_VREF";
23"TP_CH_M_DIMM_M1_RFU_2";
24"TP_CH_M_DIMM_M1_RFU_0";
25"TP_CH_M_DIMM_M1_RFU_1";
26"SMB_DDR_KLM_VPP_SCL";
27"SMB_DDR_KLM_VPP_SDA";
28"FM_ADR_COMPLETE_KLM_N";
29"FM_DIMM_EVENT_COD_N";
30"M_M_PAR";
31"M_KLM_RST_N";
32"M_M_C<2>";
33"M_M_BA<1>";
34"M_M_CS_N<7>";
35"M_M_CS_N<6>";
36"M_M_CS_N<5>";
37"M_M_MA<0>";
38"M_M_MA<3>";
39"M_M_ECC<6>";
40"M_M_ECC<5>";
41"M_M_ECC<4>";
42"M_M_ECC<3>";
43"M_M_ECC<2>";
44"M_M_ECC<1>";
45"M_M_ECC<0>";
46"M_M_CKE<3>";
47"M_M_BG<0>";
48"M_M_BG<1>";
49"M_M_BA<0>";
50"M_M_MA<2>";
51"M_M_ECC<7>";
52"M_M_ODT<2>";
53"M_M_ODT<3>";
54"M_M_CKE<2>";
55"M_M_CS_N<4>";
56"M_M_MA<1>";
57"M_M_CLK_DP<2>";
58"M_M_CLK_DP<3>";
59"M_M_CLK_DN<3>";
60"M_M_CLK_DN<2>";
61"M_M_ALERT_N";
62"M_M_ACT_N";
63"M_M_DQ<7>";
64"M_M_DQ<6>";
65"M_M_DQ<1>";
66"M_M_DQ<0>";
67"M_M_DQ<2>";
68"M_M_DQ<3>";
69"M_M_DQ<4>";
70"M_M_DQ<5>";
71"M_M_DQ<8>";
72"M_M_DQ<19>";
73"M_M_DQ<18>";
74"M_M_DQ<13>";
75"M_M_DQ<9>";
76"M_M_DQ<17>";
77"M_M_DQ<10>";
78"M_M_DQ<11>";
79"M_M_DQ<12>";
80"M_M_DQ<14>";
81"M_M_DQ<15>";
82"M_M_DQ<16>";
83"M_M_DQ<29>";
84"M_M_DQ<28>";
85"M_M_DQ<25>";
86"M_M_DQ<24>";
87"M_M_DQ<23>";
88"M_M_DQ<21>";
89"M_M_DQ<20>";
90"M_M_DQ<27>";
91"M_M_DQ<26>";
92"M_M_DQ<22>";
93"M_M_DQ<39>";
94"M_M_DQ<37>";
95"M_M_DQ<34>";
96"M_M_DQ<33>";
97"M_M_DQ<32>";
98"M_M_DQ<31>";
99"M_M_DQ<35>";
100"M_M_DQ<36>";
101"M_M_DQ<38>";
102"M_M_DQ<30>";
103"M_M_DQ<46>";
104"M_M_DQ<45>";
105"M_M_DQ<44>";
106"M_M_DQ<43>";
107"M_M_DQ<42>";
108"M_M_DQ<41>";
109"M_M_DQ<40>";
110"M_M_DQ<49>";
111"M_M_DQ<48>";
112"M_M_DQ<47>";
113"M_M_MA<12>";
114"M_M_MA<13>";
115"M_M_MA<17>";
116"M_M_MA<5>";
117"M_M_MA<6>";
118"M_M_MA<7>";
119"M_M_MA<8>";
120"M_M_MA<9>";
121"M_M_MA<10>";
122"M_M_MA<11>";
123"M_M_MA<14>";
124"M_M_MA<15>";
125"M_M_MA<16>";
126"M_M_MA<4>";
127"M_M_DQ<59>";
128"M_M_DQ<56>";
129"M_M_DQ<55>";
130"M_M_DQ<54>";
131"M_M_DQ<53>";
132"M_M_DQ<52>";
133"M_M_DQ<51>";
134"M_M_DQ<50>";
135"M_M_DQ<57>";
136"M_M_DQ<58>";
137"M_M_DQ<60>";
138"M_M_DQ<62>";
139"M_M_DQ<61>";
140"M_M_DQ<63>";
141"M_M_DQS_DN<0>";
142"M_M_DQS_DP<0>";
143"M_M_DQS_DN<1>";
144"M_M_DQS_DP<1>";
145"M_M_DQS_DN<2>";
146"M_M_DQS_DP<2>";
147"M_M_DQS_DN<3>";
148"M_M_DQS_DP<3>";
149"M_M_DQS_DN<4>";
150"M_M_DQS_DP<4>";
151"M_M_DQS_DN<5>";
152"M_M_DQS_DP<5>";
153"M_M_DQS_DN<6>";
154"M_M_DQS_DP<6>";
155"M_M_DQS_DN<10>";
156"M_M_DQS_DP<10>";
157"M_M_DQS_DN<11>";
158"M_M_DQS_DP<11>";
159"M_M_DQS_DN<12>";
160"M_M_DQS_DP<12>";
161"M_M_DQS_DN<13>";
162"M_M_DQS_DP<13>";
163"M_M_DQS_DN<14>";
164"M_M_DQS_DP<14>";
165"M_M_DQS_DN<15>";
166"M_M_DQS_DP<15>";
167"M_M_DQS_DN<16>";
168"M_M_DQS_DP<16>";
169"M_M_DQS_DN<17>";
170"M_M_DQS_DN<7>";
171"M_M_DQS_DP<7>";
172"M_M_DQS_DN<8>";
173"M_M_DQS_DP<8>";
174"M_M_DQS_DN<9>";
175"M_M_DQS_DP<9>";
176"M_M_DQS_DP<17>";
%"TAP"
"6","(-1700,2050)","2","mstr_standard","I100";
;
HDL_TAP"TRUE"
BODY_TYPE"PLUMBING"
CDS_LIB"mstr_standard";
"B \NAC \NWC"4;
"S \NAC"
BN"9"75;
%"TAP"
"6","(-1700,2150)","2","mstr_standard","I101";
;
HDL_TAP"TRUE"
BODY_TYPE"PLUMBING"
CDS_LIB"mstr_standard";
"B \NAC \NWC"4;
"S \NAC"
BN"11"78;
%"TAP"
"6","(-1700,2200)","2","mstr_standard","I102";
;
HDL_TAP"TRUE"
BODY_TYPE"PLUMBING"
CDS_LIB"mstr_standard";
"B \NAC \NWC"4;
"S \NAC"
BN"12"79;
%"TAP"
"6","(-1700,1950)","2","mstr_standard","I103";
;
HDL_TAP"TRUE"
BODY_TYPE"PLUMBING"
CDS_LIB"mstr_standard";
"B \NAC \NWC"4;
"S \NAC"
BN"7"63;
%"TAP"
"6","(-1700,1900)","2","mstr_standard","I104";
;
HDL_TAP"TRUE"
BODY_TYPE"PLUMBING"
CDS_LIB"mstr_standard";
"B \NAC \NWC"4;
"S \NAC"
BN"6"64;
%"TAP"
"6","(-1700,1850)","2","mstr_standard","I105";
;
HDL_TAP"TRUE"
BODY_TYPE"PLUMBING"
CDS_LIB"mstr_standard";
"B \NAC \NWC"4;
"S \NAC"
BN"5"70;
%"TAP"
"6","(-1700,1800)","2","mstr_standard","I106";
;
HDL_TAP"TRUE"
BODY_TYPE"PLUMBING"
CDS_LIB"mstr_standard";
"B \NAC \NWC"4;
"S \NAC"
BN"4"69;
%"TAP"
"6","(-1700,1750)","2","mstr_standard","I107";
;
HDL_TAP"TRUE"
BODY_TYPE"PLUMBING"
CDS_LIB"mstr_standard";
"B \NAC \NWC"4;
"S \NAC"
BN"3"68;
%"TAP"
"6","(-1700,1600)","2","mstr_standard","I108";
;
HDL_TAP"TRUE"
BODY_TYPE"PLUMBING"
CDS_LIB"mstr_standard";
"B \NAC \NWC"4;
"S \NAC"
BN"0"66;
%"TAP"
"6","(-1700,1700)","2","mstr_standard","I109";
;
HDL_TAP"TRUE"
BODY_TYPE"PLUMBING"
CDS_LIB"mstr_standard";
"B \NAC \NWC"4;
"S \NAC"
BN"2"67;
%"PVDDQ_KLM"
"1","(-1350,2550)","0","mstr_symbols","I11";
;
HDL_POWER"PVDDQ_KLM"
ROOM"PROC"
BODY_TYPE"PLUMBING"
CDS_LIB"mstr_symbols"
BOM_COST"PROC"
VOLTAGE"1.2V";
"G\NAC"13;
%"TAP"
"6","(-1700,1650)","2","mstr_standard","I110";
;
HDL_TAP"TRUE"
BODY_TYPE"PLUMBING"
CDS_LIB"mstr_standard";
"B \NAC \NWC"4;
"S \NAC"
BN"1"65;
%"SCONN288_H44441003"
"1","(-2450,3100)","0","mstr_sconn","I111";
;
CDS_SEC"1"
ROOM"DDR4_CH_M"
CDS_LOCATION"J9L1"
SEC"1"
BOM_COST"DDR4_CH_M"
CDS_LIB"mstr_sconn"
SEC_TYPE"PIP"
PACK_TYPE"PIP"
MATERIAL"SCONN"
PART_NUMBER"H44441-003"
LOCATION"J9L1";
"DQ<63>"
$PN"280"140;
"BA<1>"
$PN"224"33;
"CK1N"
$PN"219"59;
"CK0P"
$PN"74"57;
"S3_N_C<1>"
$PN"237"34;
"S2_N_C<0>"
$PN"93"35;
"S1_N"
$PN"89"36;
"DQ<29>"
$PN"181"83;
"DQ<28>"
$PN"36"84;
"C<2>"
$PN"235"32;
"A0"
$PN"79"37;
"A1"
$PN"72"56;
"A12"
$PN"65"113;
"A13"
$PN"232"114;
"A17"
$PN"234"115;
"A3"
$PN"71"38;
"A4"
$PN"214"126;
"A5"
$PN"213"116;
"A6"
$PN"69"117;
"A7"
$PN"211"118;
"A8"
$PN"68"119;
"A9"
$PN"66"120;
"CB<6>"
$PN"54"39;
"CB<5>"
$PN"192"40;
"CB<4>"
$PN"47"41;
"CB<3>"
$PN"201"42;
"CB<2>"
$PN"56"43;
"CB<1>"
$PN"194"44;
"CB<0>"
$PN"49"45;
"CK0N"
$PN"75"60;
"CKE<1>"
$PN"203"46;
"DQ<62>"
$PN"135"138;
"DQ<61>"
$PN"273"139;
"DQ<60>"
$PN"128"137;
"DQ<59>"
$PN"282"127;
"DQ<56>"
$PN"130"128;
"DQ<55>"
$PN"269"129;
"DQ<46>"
$PN"113"103;
"DQ<45>"
$PN"251"104;
"DQ<44>"
$PN"106"105;
"DQ<43>"
$PN"260"106;
"DQ<42>"
$PN"115"107;
"DQ<41>"
$PN"253"108;
"DQ<40>"
$PN"108"109;
"DQ<39>"
$PN"247"93;
"DQ<37>"
$PN"240"94;
"DQ<34>"
$PN"104"95;
"DQ<33>"
$PN"242"96;
"DQ<32>"
$PN"97"97;
"DQ<31>"
$PN"188"98;
"DQ<30>"
$PN"43"102;
"DQ<25>"
$PN"183"85;
"DQ<24>"
$PN"38"86;
"DQ<23>"
$PN"177"87;
"DQ<22>"
$PN"32"92;
"DQ<21>"
$PN"170"88;
"DQ<20>"
$PN"25"89;
"DQ<19>"
$PN"179"72;
"DQ<18>"
$PN"34"73;
"DQ<16>"
$PN"27"82;
"DQ<14>"
$PN"21"80;
"DQ<13>"
$PN"159"74;
"DQ<12>"
$PN"14"79;
"DQ<11>"
$PN"168"78;
"DQ<10>"
$PN"23"77;
"DQ<9>"
$PN"161"75;
"DQ<8>"
$PN"16"71;
"DQ<7>"
$PN"155"63;
"DQ<6>"
$PN"10"64;
"EVENT_N"
$PN"78"29;
"PAR"
$PN"222"30;
"RESET_N"
$PN"58"31;
"RFU<2>"
$PN"144"23;
"SCL"
$PN"141"26;
"SDA"
$PN"285"27;
"VREFCA"
$PN"146"22;
"CK1P"
$PN"218"58;
"BG<0>"
$PN"63"47;
"BG<1>"
$PN"207"48;
"BA<0>"
$PN"81"49;
"SA<0>"
$PN"139"17;
"VDDSPD"
$PN"284"17;
"SA<2>"
$PN"238"17;
"SA<1>"
$PN"140"15;
"DQ<1>"
$PN"150"65;
"DQ<0>"
$PN"5"66;
"ACT_N"
$PN"62"62;
"ALERT_N"
$PN"208"61;
"A2"
$PN"216"50;
"DQ<35>"
$PN"249"99;
"DQ<36>"
$PN"95"100;
"DQ<38>"
$PN"102"101;
"A10"
$PN"225"121;
"A11"
$PN"210"122;
"A14_WE_N"
$PN"228"123;
"A15_CAS_N"
$PN"86"124;
"A16_RAS_N"
$PN"82"125;
"CB<7>"
$PN"199"51;
"ODT<0>"
$PN"87"52;
"ODT<1>"
$PN"91"53;
"CKE<0>"
$PN"60"54;
"S0_N"
$PN"84"55;
"DQ<27>"
$PN"190"90;
"DQ<26>"
$PN"45"91;
"DQ<15>"
$PN"166"81;
"DQ<17>"
$PN"172"76;
"RFU<0>"
$PN"205"24;
"RFU<1>"
$PN"227"25;
"SAVE_N_NC"
$PN"230"28;
"DQ<57>"
$PN"275"135;
"DQ<58>"
$PN"137"136;
"DQ<54>"
$PN"124"130;
"DQ<53>"
$PN"262"131;
"DQ<52>"
$PN"117"132;
"DQ<51>"
$PN"271"133;
"DQ<50>"
$PN"126"134;
"DQ<49>"
$PN"264"110;
"DQ<48>"
$PN"119"111;
"DQ<47>"
$PN"258"112;
"DQ<2>"
$PN"12"67;
"DQ<3>"
$PN"157"68;
"DQ<4>"
$PN"3"69;
"DQ<5>"
$PN"148"70;
%"TAP"
"6","(-3200,4700)","0","mstr_standard","I112";
;
HDL_TAP"TRUE"
BODY_TYPE"PLUMBING"
CDS_LIB"mstr_standard";
"B \NAC \NWC"3;
"S \NAC"
BN"16"125;
%"TAP"
"6","(-3200,4750)","0","mstr_standard","I113";
;
HDL_TAP"TRUE"
BODY_TYPE"PLUMBING"
CDS_LIB"mstr_standard";
"B \NAC \NWC"3;
"S \NAC"
BN"17"115;
%"TAP"
"6","(-3200,4650)","0","mstr_standard","I114";
;
HDL_TAP"TRUE"
BODY_TYPE"PLUMBING"
CDS_LIB"mstr_standard";
"B \NAC \NWC"3;
"S \NAC"
BN"15"124;
%"TAP"
"6","(-3200,4600)","0","mstr_standard","I115";
;
HDL_TAP"TRUE"
BODY_TYPE"PLUMBING"
CDS_LIB"mstr_standard";
"B \NAC \NWC"3;
"S \NAC"
BN"14"123;
%"TAP"
"6","(-3200,4550)","0","mstr_standard","I116";
;
HDL_TAP"TRUE"
BODY_TYPE"PLUMBING"
CDS_LIB"mstr_standard";
"B \NAC \NWC"3;
"S \NAC"
BN"13"114;
%"TAP"
"6","(-3200,4500)","0","mstr_standard","I117";
;
HDL_TAP"TRUE"
BODY_TYPE"PLUMBING"
CDS_LIB"mstr_standard";
"B \NAC \NWC"3;
"S \NAC"
BN"12"113;
%"TAP"
"6","(-3200,4450)","0","mstr_standard","I118";
;
HDL_TAP"TRUE"
BODY_TYPE"PLUMBING"
CDS_LIB"mstr_standard";
"B \NAC \NWC"3;
"S \NAC"
BN"11"122;
%"TAP"
"6","(-3200,4400)","0","mstr_standard","I119";
;
HDL_TAP"TRUE"
BODY_TYPE"PLUMBING"
CDS_LIB"mstr_standard";
"B \NAC \NWC"3;
"S \NAC"
BN"10"121;
%"TAP"
"6","(900,4500)","2","mstr_standard","I12";
;
HDL_TAP"TRUE"
BODY_TYPE"PLUMBING"
CDS_LIB"mstr_standard";
"B \NAC \NWC"2;
"S \NAC"
BN"11"157;
%"TAP"
"6","(-3200,4300)","0","mstr_standard","I120";
;
HDL_TAP"TRUE"
BODY_TYPE"PLUMBING"
CDS_LIB"mstr_standard";
"B \NAC \NWC"3;
"S \NAC"
BN"8"119;
%"TAP"
"6","(-3200,4350)","0","mstr_standard","I121";
;
HDL_TAP"TRUE"
BODY_TYPE"PLUMBING"
CDS_LIB"mstr_standard";
"B \NAC \NWC"3;
"S \NAC"
BN"9"120;
%"TAP"
"6","(-3200,4250)","0","mstr_standard","I122";
;
HDL_TAP"TRUE"
BODY_TYPE"PLUMBING"
CDS_LIB"mstr_standard";
"B \NAC \NWC"3;
"S \NAC"
BN"7"118;
%"TAP"
"6","(-3200,4200)","0","mstr_standard","I123";
;
HDL_TAP"TRUE"
BODY_TYPE"PLUMBING"
CDS_LIB"mstr_standard";
"B \NAC \NWC"3;
"S \NAC"
BN"6"117;
%"TAP"
"6","(-3200,4150)","0","mstr_standard","I124";
;
HDL_TAP"TRUE"
BODY_TYPE"PLUMBING"
CDS_LIB"mstr_standard";
"B \NAC \NWC"3;
"S \NAC"
BN"5"116;
%"TAP"
"6","(-3200,4100)","0","mstr_standard","I125";
;
HDL_TAP"TRUE"
BODY_TYPE"PLUMBING"
CDS_LIB"mstr_standard";
"B \NAC \NWC"3;
"S \NAC"
BN"4"126;
%"TAP"
"6","(-3200,4050)","0","mstr_standard","I126";
;
HDL_TAP"TRUE"
BODY_TYPE"PLUMBING"
CDS_LIB"mstr_standard";
"B \NAC \NWC"3;
"S \NAC"
BN"3"38;
%"TAP"
"6","(-3200,4000)","0","mstr_standard","I127";
;
HDL_TAP"TRUE"
BODY_TYPE"PLUMBING"
CDS_LIB"mstr_standard";
"B \NAC \NWC"3;
"S \NAC"
BN"2"50;
%"TAP"
"6","(-3200,3950)","0","mstr_standard","I128";
;
HDL_TAP"TRUE"
BODY_TYPE"PLUMBING"
CDS_LIB"mstr_standard";
"B \NAC \NWC"3;
"S \NAC"
BN"1"56;
%"TAP"
"6","(-3200,3900)","0","mstr_standard","I129";
;
HDL_TAP"TRUE"
BODY_TYPE"PLUMBING"
CDS_LIB"mstr_standard";
"B \NAC \NWC"3;
"S \NAC"
BN"0"37;
%"TAP"
"6","(900,4400)","2","mstr_standard","I13";
;
HDL_TAP"TRUE"
BODY_TYPE"PLUMBING"
CDS_LIB"mstr_standard";
"B \NAC \NWC"2;
"S \NAC"
BN"10"155;
%"TAP"
"6","(-3200,3800)","0","mstr_standard","I130";
;
HDL_TAP"TRUE"
BODY_TYPE"PLUMBING"
CDS_LIB"mstr_standard";
"B \NAC \NWC"10;
"S \NAC"
BN"1"33;
%"TAP"
"6","(-3200,3750)","0","mstr_standard","I133";
;
HDL_TAP"TRUE"
BODY_TYPE"PLUMBING"
CDS_LIB"mstr_standard";
"B \NAC \NWC"10;
"S \NAC"
BN"0"49;
%"TAP"
"6","(-3200,3650)","0","mstr_standard","I134";
;
HDL_TAP"TRUE"
BODY_TYPE"PLUMBING"
CDS_LIB"mstr_standard";
"B \NAC \NWC"11;
"S \NAC"
BN"0"47;
%"TAP"
"6","(-3200,3700)","0","mstr_standard","I135";
;
HDL_TAP"TRUE"
BODY_TYPE"PLUMBING"
CDS_LIB"mstr_standard";
"B \NAC \NWC"11;
"S \NAC"
BN"1"48;
%"TAP"
"6","(-3200,2650)","0","mstr_standard","I138";
;
HDL_TAP"TRUE"
BODY_TYPE"PLUMBING"
CDS_LIB"mstr_standard";
"B \NAC \NWC"12;
"S \NAC"
BN"6"39;
%"TAP"
"6","(-3200,2700)","0","mstr_standard","I139";
;
HDL_TAP"TRUE"
BODY_TYPE"PLUMBING"
CDS_LIB"mstr_standard";
"B \NAC \NWC"12;
"S \NAC"
BN"7"51;
%"TAP"
"6","(900,4300)","2","mstr_standard","I14";
;
HDL_TAP"TRUE"
BODY_TYPE"PLUMBING"
CDS_LIB"mstr_standard";
"B \NAC \NWC"2;
"S \NAC"
BN"9"174;
%"TAP"
"6","(-3200,2600)","0","mstr_standard","I140";
;
HDL_TAP"TRUE"
BODY_TYPE"PLUMBING"
CDS_LIB"mstr_standard";
"B \NAC \NWC"12;
"S \NAC"
BN"5"40;
%"TAP"
"6","(-3200,2550)","0","mstr_standard","I141";
;
HDL_TAP"TRUE"
BODY_TYPE"PLUMBING"
CDS_LIB"mstr_standard";
"B \NAC \NWC"12;
"S \NAC"
BN"4"41;
%"TAP"
"6","(-3200,2500)","0","mstr_standard","I142";
;
HDL_TAP"TRUE"
BODY_TYPE"PLUMBING"
CDS_LIB"mstr_standard";
"B \NAC \NWC"12;
"S \NAC"
BN"3"42;
%"TAP"
"6","(-3200,2450)","0","mstr_standard","I143";
;
HDL_TAP"TRUE"
BODY_TYPE"PLUMBING"
CDS_LIB"mstr_standard";
"B \NAC \NWC"12;
"S \NAC"
BN"2"43;
%"TAP"
"6","(-3200,2400)","0","mstr_standard","I144";
;
HDL_TAP"TRUE"
BODY_TYPE"PLUMBING"
CDS_LIB"mstr_standard";
"B \NAC \NWC"12;
"S \NAC"
BN"1"44;
%"TAP"
"6","(-3200,2350)","0","mstr_standard","I145";
;
HDL_TAP"TRUE"
BODY_TYPE"PLUMBING"
CDS_LIB"mstr_standard";
"B \NAC \NWC"12;
"S \NAC"
BN"0"45;
%"TAP"
"6","(900,4200)","2","mstr_standard","I15";
;
HDL_TAP"TRUE"
BODY_TYPE"PLUMBING"
CDS_LIB"mstr_standard";
"B \NAC \NWC"2;
"S \NAC"
BN"8"172;
%"TAP"
"6","(-3650,3450)","0","mstr_standard","I152";
;
HDL_TAP"TRUE"
BODY_TYPE"PLUMBING"
CDS_LIB"mstr_standard";
"B \NAC \NWC"6;
"S \NAC"
BN"2"57;
%"TAP"
"6","(-3800,3400)","0","mstr_standard","I153";
;
HDL_TAP"TRUE"
BODY_TYPE"PLUMBING"
CDS_LIB"mstr_standard";
"B \NAC \NWC"5;
"S \NAC"
BN"2"60;
%"TAP"
"6","(900,4100)","2","mstr_standard","I16";
;
HDL_TAP"TRUE"
BODY_TYPE"PLUMBING"
CDS_LIB"mstr_standard";
"B \NAC \NWC"2;
"S \NAC"
BN"7"170;
%"TAP"
"6","(-3200,3250)","0","mstr_standard","I160";
;
HDL_TAP"TRUE"
BODY_TYPE"PLUMBING"
CDS_LIB"mstr_standard";
"B \NAC \NWC"7;
"S \NAC"
BN"7"34;
%"TAP"
"6","(-3200,3200)","0","mstr_standard","I161";
;
HDL_TAP"TRUE"
BODY_TYPE"PLUMBING"
CDS_LIB"mstr_standard";
"B \NAC \NWC"7;
"S \NAC"
BN"6"35;
%"TAP"
"6","(-3200,3150)","0","mstr_standard","I162";
;
HDL_TAP"TRUE"
BODY_TYPE"PLUMBING"
CDS_LIB"mstr_standard";
"B \NAC \NWC"7;
"S \NAC"
BN"5"36;
%"TAP"
"6","(-3200,3100)","0","mstr_standard","I163";
;
HDL_TAP"TRUE"
BODY_TYPE"PLUMBING"
CDS_LIB"mstr_standard";
"B \NAC \NWC"7;
"S \NAC"
BN"4"55;
%"TAP"
"6","(-3200,3000)","0","mstr_standard","I164";
;
HDL_TAP"TRUE"
BODY_TYPE"PLUMBING"
CDS_LIB"mstr_standard";
"B \NAC \NWC"8;
"S \NAC"
BN"3"46;
%"TAP"
"6","(-3200,2950)","0","mstr_standard","I165";
;
HDL_TAP"TRUE"
BODY_TYPE"PLUMBING"
CDS_LIB"mstr_standard";
"B \NAC \NWC"8;
"S \NAC"
BN"2"54;
%"TAP"
"6","(-3200,2850)","0","mstr_standard","I166";
;
HDL_TAP"TRUE"
BODY_TYPE"PLUMBING"
CDS_LIB"mstr_standard";
"B \NAC \NWC"9;
"S \NAC"
BN"3"53;
%"TAP"
"6","(-3200,2800)","0","mstr_standard","I167";
;
HDL_TAP"TRUE"
BODY_TYPE"PLUMBING"
CDS_LIB"mstr_standard";
"B \NAC \NWC"9;
"S \NAC"
BN"2"52;
%"SCONN288_H44441003"
"4","(-300,2000)","0","mstr_sconn","I168";
;
CDS_SEC"4"
ROOM"DDR4_CH_M"
CDS_LOCATION"J9L1"
SEC"4"
BOM_COST"MEM"
CDS_LIB"mstr_sconn"
SEC_TYPE"PIP"
PACK_TYPE"PIP"
MATERIAL"SCONN"
PART_NUMBER"H44441-003"
LOCATION"J9L1";
"VDD<0>"
$PN"236"13;
"VDD<6>"
$PN"220"13;
"VDD<10>"
$PN"209"13;
"VDD<13>"
$PN"92"13;
"VDD<16>"
$PN"85"13;
"VDD<19>"
$PN"76"13;
"VDD<23>"
$PN"64"13;
"VDD<25>"
$PN"59"13;
"VTT<0>"
$PN"221"21;
"12V<1>"
$PN"1"19;
"12V<0>"
$PN"145"19;
"VDD<24>"
$PN"61"13;
"VDD<22>"
$PN"67"13;
"VDD<21>"
$PN"70"13;
"VDD<20>"
$PN"73"13;
"VDD<18>"
$PN"80"13;
"VDD<17>"
$PN"83"13;
"VDD<15>"
$PN"88"13;
"VDD<14>"
$PN"90"13;
"VDD<12>"
$PN"204"13;
"VDD<11>"
$PN"206"13;
"VDD<9>"
$PN"212"13;
"VDD<8>"
$PN"215"13;
"VDD<7>"
$PN"217"13;
"VDD<5>"
$PN"223"13;
"VDD<4>"
$PN"226"13;
"VDD<3>"
$PN"229"13;
"VDD<2>"
$PN"231"13;
"VDD<1>"
$PN"233"13;
"VPP<4>"
$PN"142"18;
"VPP<3>"
$PN"143"18;
"VPP<2>"
$PN"288"18;
"VPP<1>"
$PN"286"18;
"VPP<0>"
$PN"287"18;
"VTT<1>"
$PN"77"21;
%"GND"
"1","(2500,1100)","2","mstr_symbols","I169";
;
HDL_POWER"GND"
ROOM"DDR4_CH_D"
BODY_TYPE"PLUMBING"
BOM_COST"MEM"
SIZE"1B"
CDS_LIB"mstr_symbols"
VOLTAGE"0";
"A\NAC"14;
%"TAP"
"6","(900,4000)","2","mstr_standard","I17";
;
HDL_TAP"TRUE"
BODY_TYPE"PLUMBING"
CDS_LIB"mstr_standard";
"B \NAC \NWC"2;
"S \NAC"
BN"6"153;
%"GND"
"1","(-5200,1725)","2","mstr_symbols","I175";
;
HDL_POWER"GND"
ROOM"DDR4_CH_D"
BODY_TYPE"PLUMBING"
SIZE"1B"
CDS_LIB"mstr_symbols"
BOM_COST"MEM"
VOLTAGE"0";
"A\NAC"15;
%"GND"
"1","(-4650,1150)","0","mstr_symbols","I176";
;
HDL_POWER"GND"
ROOM"DDR4_CH_D"
BODY_TYPE"PLUMBING"
BOM_COST"MEM"
CDS_LIB"mstr_symbols"
SIZE"1B"
VOLTAGE"0";
"A\NAC"16;
%"CAP_A"
"1","(-4650,1400)","2","dev_discrete","I177";
;
ROOM"DDR4_CH_M1"
SEC"1"
SEC_TYPE"0402V"
CDS_SEC"1"
CDS_LIB"dev_discrete"
BOM_COST"MEM"
CDS_LOCATION"C9L1"
MATERIAL"X7R"
VOLTAGE"25V"
PACK_TYPE"0402V"
TOLERANCE"10%"
VALUE"0.01UF"
PART_NUMBER"A36096-045"
LOCATION"C9L1";
"B"
$PN"2"16;
"A"
$PN"1"22;
%"PVPP_KLM"
"1","(-5200,2100)","0","mstr_symbols","I178";
;
HDL_POWER"PVPP_KLM"
ROOM"DDR4_CH_D"
BODY_TYPE"PLUMBING"
CDS_LIB"mstr_symbols"
BOM_COST"MEM"
VOLTAGE"2.5V";
"G\NAC"17;
%"PVPP_KLM"
"1","(-1000,3025)","0","mstr_symbols","I179";
;
HDL_POWER"PVPP_KLM"
ROOM"DDR4_CH_D"
BODY_TYPE"PLUMBING"
CDS_LIB"mstr_symbols"
BOM_COST"MEM"
VOLTAGE"2.5V";
"G\NAC"18;
%"TAP"
"6","(900,3900)","2","mstr_standard","I18";
;
HDL_TAP"TRUE"
BODY_TYPE"PLUMBING"
CDS_LIB"mstr_standard";
"B \NAC \NWC"2;
"S \NAC"
BN"5"151;
%"TAP"
"6","(-3650,3550)","0","mstr_standard","I184";
;
HDL_TAP"TRUE"
BODY_TYPE"PLUMBING"
CDS_LIB"mstr_standard";
"B \NAC \NWC"6;
"S \NAC"
BN"3"58;
%"TAP"
"6","(-3800,3500)","0","mstr_standard","I185";
;
HDL_TAP"TRUE"
BODY_TYPE"PLUMBING"
CDS_LIB"mstr_standard";
"B \NAC \NWC"5;
"S \NAC"
BN"3"59;
%"P12V_NVDIMM_KLM"
"1","(400,3000)","0","mstr_symbols","I186";
;
HDL_POWER"P12V_NVDIMM_KLM"
BODY_TYPE"PLUMBING"
CDS_LIB"mstr_symbols"
VOLTAGE"12.0";
"G\NAC"19;
%"TAP"
"6","(900,3800)","2","mstr_standard","I19";
;
HDL_TAP"TRUE"
BODY_TYPE"PLUMBING"
CDS_LIB"mstr_standard";
"B \NAC \NWC"2;
"S \NAC"
BN"4"149;
%"TAP"
"6","(900,3700)","2","mstr_standard","I20";
;
HDL_TAP"TRUE"
BODY_TYPE"PLUMBING"
CDS_LIB"mstr_standard";
"B \NAC \NWC"2;
"S \NAC"
BN"3"147;
%"TAP"
"6","(900,3500)","2","mstr_standard","I21";
;
HDL_TAP"TRUE"
BODY_TYPE"PLUMBING"
CDS_LIB"mstr_standard";
"B \NAC \NWC"2;
"S \NAC"
BN"1"143;
%"TAP"
"6","(900,3600)","2","mstr_standard","I22";
;
HDL_TAP"TRUE"
BODY_TYPE"PLUMBING"
CDS_LIB"mstr_standard";
"B \NAC \NWC"2;
"S \NAC"
BN"2"145;
%"TAP"
"6","(900,3400)","2","mstr_standard","I23";
;
HDL_TAP"TRUE"
BODY_TYPE"PLUMBING"
CDS_LIB"mstr_standard";
"B \NAC \NWC"2;
"S \NAC"
BN"0"141;
%"SCONN288_H44441003"
"3","(1800,2400)","0","mstr_sconn","I25";
;
CDS_SEC"3"
ROOM"DDR4_CH_M"
CDS_LOCATION"J9L1"
SEC"3"
BOM_COST"DDR4_CH_M"
CDS_LIB"mstr_sconn"
SEC_TYPE"PIP"
PACK_TYPE"PIP"
MATERIAL"SCONN"
PART_NUMBER"H44441-003"
LOCATION"J9L1";
"VSS<46>"
$PN"147"14;
"VSS<45>"
$PN"149"14;
"VSS<87>"
$PN"15"20;
"VSS<86>"
$PN"17"20;
"VSS<85>"
$PN"20"20;
"VSS<84>"
$PN"22"20;
"VSS<83>"
$PN"24"20;
"VSS<82>"
$PN"26"20;
"VSS<81>"
$PN"28"20;
"VSS<80>"
$PN"31"20;
"VSS<79>"
$PN"33"20;
"VSS<78>"
$PN"35"20;
"VSS<77>"
$PN"37"20;
"VSS<76>"
$PN"39"20;
"VSS<75>"
$PN"42"20;
"VSS<74>"
$PN"44"20;
"VSS<73>"
$PN"46"20;
"VSS<72>"
$PN"48"20;
"VSS<71>"
$PN"50"20;
"VSS<70>"
$PN"53"20;
"VSS<69>"
$PN"55"20;
"VSS<68>"
$PN"57"20;
"VSS<67>"
$PN"94"20;
"VSS<66>"
$PN"96"20;
"VSS<65>"
$PN"98"20;
"VSS<64>"
$PN"101"20;
"VSS<63>"
$PN"103"20;
"VSS<62>"
$PN"105"20;
"VSS<61>"
$PN"107"20;
"VSS<60>"
$PN"109"20;
"VSS<59>"
$PN"112"20;
"VSS<58>"
$PN"114"20;
"VSS<57>"
$PN"116"20;
"VSS<56>"
$PN"118"20;
"VSS<55>"
$PN"120"20;
"VSS<54>"
$PN"123"20;
"VSS<53>"
$PN"125"20;
"VSS<52>"
$PN"127"20;
"VSS<51>"
$PN"129"20;
"VSS<50>"
$PN"131"20;
"VSS<49>"
$PN"134"20;
"VSS<48>"
$PN"136"20;
"VSS<47>"
$PN"138"20;
"VSS<44>"
$PN"151"14;
"VSS<43>"
$PN"154"14;
"VSS<42>"
$PN"156"14;
"VSS<41>"
$PN"158"14;
"VSS<40>"
$PN"160"14;
"VSS<39>"
$PN"162"14;
"VSS<38>"
$PN"165"14;
"VSS<37>"
$PN"167"14;
"VSS<36>"
$PN"169"14;
"VSS<35>"
$PN"171"14;
"VSS<34>"
$PN"173"14;
"VSS<33>"
$PN"176"14;
"VSS<32>"
$PN"178"14;
"VSS<31>"
$PN"180"14;
"VSS<30>"
$PN"182"14;
"VSS<29>"
$PN"184"14;
"VSS<28>"
$PN"187"14;
"VSS<27>"
$PN"189"14;
"VSS<26>"
$PN"191"14;
"VSS<25>"
$PN"193"14;
"VSS<24>"
$PN"195"14;
"VSS<23>"
$PN"198"14;
"VSS<22>"
$PN"200"14;
"VSS<21>"
$PN"202"14;
"VSS<20>"
$PN"239"14;
"VSS<19>"
$PN"241"14;
"VSS<18>"
$PN"243"14;
"VSS<17>"
$PN"246"14;
"VSS<16>"
$PN"248"14;
"VSS<15>"
$PN"250"14;
"VSS<14>"
$PN"252"14;
"VSS<13>"
$PN"254"14;
"VSS<12>"
$PN"257"14;
"VSS<11>"
$PN"259"14;
"VSS<10>"
$PN"261"14;
"VSS<9>"
$PN"263"14;
"VSS<8>"
$PN"265"14;
"VSS<7>"
$PN"268"14;
"VSS<6>"
$PN"270"14;
"VSS<5>"
$PN"272"14;
"VSS<4>"
$PN"274"14;
"VSS<3>"
$PN"276"14;
"VSS<2>"
$PN"279"14;
"VSS<1>"
$PN"281"14;
"VSS<0>"
$PN"283"14;
"VSS<88>"
$PN"13"20;
"VSS<89>"
$PN"11"20;
"VSS<90>"
$PN"9"20;
"VSS<91>"
$PN"6"20;
"VSS<92>"
$PN"4"20;
"VSS<93>"
$PN"2"20;
%"GND"
"1","(1100,1100)","2","mstr_symbols","I26";
;
HDL_POWER"GND"
ROOM"PROC"
BODY_TYPE"PLUMBING"
BOM_COST"PROC"
CDS_LIB"mstr_symbols"
SIZE"1B"
VOLTAGE"4V";
"A\NAC"20;
%"TAP"
"6","(700,5150)","2","mstr_standard","I27";
;
HDL_TAP"TRUE"
BODY_TYPE"PLUMBING"
CDS_LIB"mstr_standard";
"B \NAC \NWC"1;
"S \NAC"
BN"17"176;
%"TAP"
"6","(700,5050)","2","mstr_standard","I28";
;
HDL_TAP"TRUE"
BODY_TYPE"PLUMBING"
CDS_LIB"mstr_standard";
"B \NAC \NWC"1;
"S \NAC"
BN"16"168;
%"TAP"
"6","(700,4750)","2","mstr_standard","I29";
;
HDL_TAP"TRUE"
BODY_TYPE"PLUMBING"
CDS_LIB"mstr_standard";
"B \NAC \NWC"1;
"S \NAC"
BN"13"162;
%"TAP"
"6","(900,5100)","2","mstr_standard","I3";
;
HDL_TAP"TRUE"
BODY_TYPE"PLUMBING"
CDS_LIB"mstr_standard";
"B \NAC \NWC"2;
"S \NAC"
BN"17"169;
%"TAP"
"6","(700,4650)","2","mstr_standard","I30";
;
HDL_TAP"TRUE"
BODY_TYPE"PLUMBING"
CDS_LIB"mstr_standard";
"B \NAC \NWC"1;
"S \NAC"
BN"12"160;
%"TAP"
"6","(700,4550)","2","mstr_standard","I31";
;
HDL_TAP"TRUE"
BODY_TYPE"PLUMBING"
CDS_LIB"mstr_standard";
"B \NAC \NWC"1;
"S \NAC"
BN"11"158;
%"TAP"
"6","(700,4950)","2","mstr_standard","I32";
;
HDL_TAP"TRUE"
BODY_TYPE"PLUMBING"
CDS_LIB"mstr_standard";
"B \NAC \NWC"1;
"S \NAC"
BN"15"166;
%"TAP"
"6","(700,4850)","2","mstr_standard","I33";
;
HDL_TAP"TRUE"
BODY_TYPE"PLUMBING"
CDS_LIB"mstr_standard";
"B \NAC \NWC"1;
"S \NAC"
BN"14"164;
%"TAP"
"6","(-1700,4550)","2","mstr_standard","I35";
;
HDL_TAP"TRUE"
BODY_TYPE"PLUMBING"
CDS_LIB"mstr_standard";
"B \NAC \NWC"4;
"S \NAC"
BN"59"127;
%"TAP"
"6","(-1700,4750)","2","mstr_standard","I36";
;
HDL_TAP"TRUE"
BODY_TYPE"PLUMBING"
CDS_LIB"mstr_standard";
"B \NAC \NWC"4;
"S \NAC"
BN"63"140;
%"TAP"
"6","(-1700,4700)","2","mstr_standard","I37";
;
HDL_TAP"TRUE"
BODY_TYPE"PLUMBING"
CDS_LIB"mstr_standard";
"B \NAC \NWC"4;
"S \NAC"
BN"62"138;
%"TAP"
"6","(-1700,4650)","2","mstr_standard","I38";
;
HDL_TAP"TRUE"
BODY_TYPE"PLUMBING"
CDS_LIB"mstr_standard";
"B \NAC \NWC"4;
"S \NAC"
BN"61"139;
%"TAP"
"6","(-1700,4600)","2","mstr_standard","I39";
;
HDL_TAP"TRUE"
BODY_TYPE"PLUMBING"
CDS_LIB"mstr_standard";
"B \NAC \NWC"4;
"S \NAC"
BN"60"137;
%"TAP"
"6","(900,5000)","2","mstr_standard","I4";
;
HDL_TAP"TRUE"
BODY_TYPE"PLUMBING"
CDS_LIB"mstr_standard";
"B \NAC \NWC"2;
"S \NAC"
BN"16"167;
%"TAP"
"6","(-1700,4300)","2","mstr_standard","I40";
;
HDL_TAP"TRUE"
BODY_TYPE"PLUMBING"
CDS_LIB"mstr_standard";
"B \NAC \NWC"4;
"S \NAC"
BN"54"130;
%"TAP"
"6","(-1700,4450)","2","mstr_standard","I41";
;
HDL_TAP"TRUE"
BODY_TYPE"PLUMBING"
CDS_LIB"mstr_standard";
"B \NAC \NWC"4;
"S \NAC"
BN"57"135;
%"TAP"
"6","(-1700,4500)","2","mstr_standard","I42";
;
HDL_TAP"TRUE"
BODY_TYPE"PLUMBING"
CDS_LIB"mstr_standard";
"B \NAC \NWC"4;
"S \NAC"
BN"58"136;
%"TAP"
"6","(-1700,4350)","2","mstr_standard","I43";
;
HDL_TAP"TRUE"
BODY_TYPE"PLUMBING"
CDS_LIB"mstr_standard";
"B \NAC \NWC"4;
"S \NAC"
BN"55"129;
%"TAP"
"6","(-1700,4400)","2","mstr_standard","I44";
;
HDL_TAP"TRUE"
BODY_TYPE"PLUMBING"
CDS_LIB"mstr_standard";
"B \NAC \NWC"4;
"S \NAC"
BN"56"128;
%"TAP"
"6","(-1700,4050)","2","mstr_standard","I45";
;
HDL_TAP"TRUE"
BODY_TYPE"PLUMBING"
CDS_LIB"mstr_standard";
"B \NAC \NWC"4;
"S \NAC"
BN"49"110;
%"TAP"
"6","(-1700,4250)","2","mstr_standard","I46";
;
HDL_TAP"TRUE"
BODY_TYPE"PLUMBING"
CDS_LIB"mstr_standard";
"B \NAC \NWC"4;
"S \NAC"
BN"53"131;
%"TAP"
"6","(-1700,4200)","2","mstr_standard","I47";
;
HDL_TAP"TRUE"
BODY_TYPE"PLUMBING"
CDS_LIB"mstr_standard";
"B \NAC \NWC"4;
"S \NAC"
BN"52"132;
%"TAP"
"6","(-1700,4100)","2","mstr_standard","I48";
;
HDL_TAP"TRUE"
BODY_TYPE"PLUMBING"
CDS_LIB"mstr_standard";
"B \NAC \NWC"4;
"S \NAC"
BN"50"134;
%"TAP"
"6","(-1700,4150)","2","mstr_standard","I49";
;
HDL_TAP"TRUE"
BODY_TYPE"PLUMBING"
CDS_LIB"mstr_standard";
"B \NAC \NWC"4;
"S \NAC"
BN"51"133;
%"TAP"
"6","(900,4900)","2","mstr_standard","I5";
;
HDL_TAP"TRUE"
BODY_TYPE"PLUMBING"
CDS_LIB"mstr_standard";
"B \NAC \NWC"2;
"S \NAC"
BN"15"165;
%"TAP"
"6","(-1700,3950)","2","mstr_standard","I50";
;
HDL_TAP"TRUE"
BODY_TYPE"PLUMBING"
CDS_LIB"mstr_standard";
"B \NAC \NWC"4;
"S \NAC"
BN"47"112;
%"TAP"
"6","(-1700,4000)","2","mstr_standard","I51";
;
HDL_TAP"TRUE"
BODY_TYPE"PLUMBING"
CDS_LIB"mstr_standard";
"B \NAC \NWC"4;
"S \NAC"
BN"48"111;
%"TAP"
"6","(-1700,3900)","2","mstr_standard","I52";
;
HDL_TAP"TRUE"
BODY_TYPE"PLUMBING"
CDS_LIB"mstr_standard";
"B \NAC \NWC"4;
"S \NAC"
BN"46"103;
%"TAP"
"6","(-1700,3800)","2","mstr_standard","I53";
;
HDL_TAP"TRUE"
BODY_TYPE"PLUMBING"
CDS_LIB"mstr_standard";
"B \NAC \NWC"4;
"S \NAC"
BN"44"105;
%"TAP"
"6","(-1700,3850)","2","mstr_standard","I54";
;
HDL_TAP"TRUE"
BODY_TYPE"PLUMBING"
CDS_LIB"mstr_standard";
"B \NAC \NWC"4;
"S \NAC"
BN"45"104;
%"TAP"
"6","(700,4250)","2","mstr_standard","I55";
;
HDL_TAP"TRUE"
BODY_TYPE"PLUMBING"
CDS_LIB"mstr_standard";
"B \NAC \NWC"1;
"S \NAC"
BN"8"173;
%"TAP"
"6","(700,4150)","2","mstr_standard","I56";
;
HDL_TAP"TRUE"
BODY_TYPE"PLUMBING"
CDS_LIB"mstr_standard";
"B \NAC \NWC"1;
"S \NAC"
BN"7"171;
%"TAP"
"6","(700,4050)","2","mstr_standard","I57";
;
HDL_TAP"TRUE"
BODY_TYPE"PLUMBING"
CDS_LIB"mstr_standard";
"B \NAC \NWC"1;
"S \NAC"
BN"6"154;
%"TAP"
"6","(700,4350)","2","mstr_standard","I58";
;
HDL_TAP"TRUE"
BODY_TYPE"PLUMBING"
CDS_LIB"mstr_standard";
"B \NAC \NWC"1;
"S \NAC"
BN"9"175;
%"TAP"
"6","(700,4450)","2","mstr_standard","I59";
;
HDL_TAP"TRUE"
BODY_TYPE"PLUMBING"
CDS_LIB"mstr_standard";
"B \NAC \NWC"1;
"S \NAC"
BN"10"156;
%"TAP"
"6","(900,4800)","2","mstr_standard","I6";
;
HDL_TAP"TRUE"
BODY_TYPE"PLUMBING"
CDS_LIB"mstr_standard";
"B \NAC \NWC"2;
"S \NAC"
BN"14"163;
%"TAP"
"6","(700,3750)","2","mstr_standard","I60";
;
HDL_TAP"TRUE"
BODY_TYPE"PLUMBING"
CDS_LIB"mstr_standard";
"B \NAC \NWC"1;
"S \NAC"
BN"3"148;
%"TAP"
"6","(700,3550)","2","mstr_standard","I61";
;
HDL_TAP"TRUE"
BODY_TYPE"PLUMBING"
CDS_LIB"mstr_standard";
"B \NAC \NWC"1;
"S \NAC"
BN"1"144;
%"TAP"
"6","(700,3650)","2","mstr_standard","I62";
;
HDL_TAP"TRUE"
BODY_TYPE"PLUMBING"
CDS_LIB"mstr_standard";
"B \NAC \NWC"1;
"S \NAC"
BN"2"146;
%"TAP"
"6","(700,3950)","2","mstr_standard","I63";
;
HDL_TAP"TRUE"
BODY_TYPE"PLUMBING"
CDS_LIB"mstr_standard";
"B \NAC \NWC"1;
"S \NAC"
BN"5"152;
%"TAP"
"6","(700,3850)","2","mstr_standard","I64";
;
HDL_TAP"TRUE"
BODY_TYPE"PLUMBING"
CDS_LIB"mstr_standard";
"B \NAC \NWC"1;
"S \NAC"
BN"4"150;
%"TAP"
"6","(700,3450)","2","mstr_standard","I65";
;
HDL_TAP"TRUE"
BODY_TYPE"PLUMBING"
CDS_LIB"mstr_standard";
"B \NAC \NWC"1;
"S \NAC"
BN"0"142;
%"TAP"
"6","(-1700,3750)","2","mstr_standard","I66";
;
HDL_TAP"TRUE"
BODY_TYPE"PLUMBING"
CDS_LIB"mstr_standard";
"B \NAC \NWC"4;
"S \NAC"
BN"43"106;
%"TAP"
"6","(-1700,3700)","2","mstr_standard","I67";
;
HDL_TAP"TRUE"
BODY_TYPE"PLUMBING"
CDS_LIB"mstr_standard";
"B \NAC \NWC"4;
"S \NAC"
BN"42"107;
%"TAP"
"6","(-1700,3600)","2","mstr_standard","I68";
;
HDL_TAP"TRUE"
BODY_TYPE"PLUMBING"
CDS_LIB"mstr_standard";
"B \NAC \NWC"4;
"S \NAC"
BN"40"109;
%"TAP"
"6","(-1700,3650)","2","mstr_standard","I69";
;
HDL_TAP"TRUE"
BODY_TYPE"PLUMBING"
CDS_LIB"mstr_standard";
"B \NAC \NWC"4;
"S \NAC"
BN"41"108;
%"TAP"
"6","(900,4700)","2","mstr_standard","I7";
;
HDL_TAP"TRUE"
BODY_TYPE"PLUMBING"
CDS_LIB"mstr_standard";
"B \NAC \NWC"2;
"S \NAC"
BN"13"161;
%"TAP"
"6","(-1700,3550)","2","mstr_standard","I70";
;
HDL_TAP"TRUE"
BODY_TYPE"PLUMBING"
CDS_LIB"mstr_standard";
"B \NAC \NWC"4;
"S \NAC"
BN"39"93;
%"TAP"
"6","(-1700,3500)","2","mstr_standard","I71";
;
HDL_TAP"TRUE"
BODY_TYPE"PLUMBING"
CDS_LIB"mstr_standard";
"B \NAC \NWC"4;
"S \NAC"
BN"38"101;
%"TAP"
"6","(-1700,3450)","2","mstr_standard","I72";
;
HDL_TAP"TRUE"
BODY_TYPE"PLUMBING"
CDS_LIB"mstr_standard";
"B \NAC \NWC"4;
"S \NAC"
BN"37"94;
%"TAP"
"6","(-1700,3400)","2","mstr_standard","I73";
;
HDL_TAP"TRUE"
BODY_TYPE"PLUMBING"
CDS_LIB"mstr_standard";
"B \NAC \NWC"4;
"S \NAC"
BN"36"100;
%"TAP"
"6","(-1700,3350)","2","mstr_standard","I74";
;
HDL_TAP"TRUE"
BODY_TYPE"PLUMBING"
CDS_LIB"mstr_standard";
"B \NAC \NWC"4;
"S \NAC"
BN"35"99;
%"TAP"
"6","(-1700,3300)","2","mstr_standard","I75";
;
HDL_TAP"TRUE"
BODY_TYPE"PLUMBING"
CDS_LIB"mstr_standard";
"B \NAC \NWC"4;
"S \NAC"
BN"34"95;
%"TAP"
"6","(-1700,3250)","2","mstr_standard","I76";
;
HDL_TAP"TRUE"
BODY_TYPE"PLUMBING"
CDS_LIB"mstr_standard";
"B \NAC \NWC"4;
"S \NAC"
BN"33"96;
%"TAP"
"6","(-1700,3200)","2","mstr_standard","I77";
;
HDL_TAP"TRUE"
BODY_TYPE"PLUMBING"
CDS_LIB"mstr_standard";
"B \NAC \NWC"4;
"S \NAC"
BN"32"97;
%"TAP"
"6","(-1700,3050)","2","mstr_standard","I78";
;
HDL_TAP"TRUE"
BODY_TYPE"PLUMBING"
CDS_LIB"mstr_standard";
"B \NAC \NWC"4;
"S \NAC"
BN"29"83;
%"TAP"
"6","(-1700,3100)","2","mstr_standard","I79";
;
HDL_TAP"TRUE"
BODY_TYPE"PLUMBING"
CDS_LIB"mstr_standard";
"B \NAC \NWC"4;
"S \NAC"
BN"30"102;
%"TAP"
"6","(900,4600)","2","mstr_standard","I8";
;
HDL_TAP"TRUE"
BODY_TYPE"PLUMBING"
CDS_LIB"mstr_standard";
"B \NAC \NWC"2;
"S \NAC"
BN"12"159;
%"TAP"
"6","(-1700,3150)","2","mstr_standard","I80";
;
HDL_TAP"TRUE"
BODY_TYPE"PLUMBING"
CDS_LIB"mstr_standard";
"B \NAC \NWC"4;
"S \NAC"
BN"31"98;
%"TAP"
"6","(-1700,2750)","2","mstr_standard","I81";
;
HDL_TAP"TRUE"
BODY_TYPE"PLUMBING"
CDS_LIB"mstr_standard";
"B \NAC \NWC"4;
"S \NAC"
BN"23"87;
%"TAP"
"6","(-1700,2950)","2","mstr_standard","I82";
;
HDL_TAP"TRUE"
BODY_TYPE"PLUMBING"
CDS_LIB"mstr_standard";
"B \NAC \NWC"4;
"S \NAC"
BN"27"90;
%"TAP"
"6","(-1700,3000)","2","mstr_standard","I83";
;
HDL_TAP"TRUE"
BODY_TYPE"PLUMBING"
CDS_LIB"mstr_standard";
"B \NAC \NWC"4;
"S \NAC"
BN"28"84;
%"TAP"
"6","(-1700,2900)","2","mstr_standard","I84";
;
HDL_TAP"TRUE"
BODY_TYPE"PLUMBING"
CDS_LIB"mstr_standard";
"B \NAC \NWC"4;
"S \NAC"
BN"26"91;
%"TAP"
"6","(-1700,2850)","2","mstr_standard","I85";
;
HDL_TAP"TRUE"
BODY_TYPE"PLUMBING"
CDS_LIB"mstr_standard";
"B \NAC \NWC"4;
"S \NAC"
BN"25"85;
%"TAP"
"6","(-1700,2800)","2","mstr_standard","I86";
;
HDL_TAP"TRUE"
BODY_TYPE"PLUMBING"
CDS_LIB"mstr_standard";
"B \NAC \NWC"4;
"S \NAC"
BN"24"86;
%"SCONN288_H44441003"
"2","(0,4300)","0","mstr_sconn","I87";
;
CDS_SEC"2"
ROOM"DDR4_CH_M"
CDS_LOCATION"J9L1"
SEC"2"
BOM_COST"DDR4_CH_M"
CDS_LIB"mstr_sconn"
SEC_TYPE"PIP"
PACK_TYPE"PIP"
MATERIAL"SCONN"
PART_NUMBER"H44441-003"
LOCATION"J9L1";
"DQS0N"
$PN"152"141;
"DQS0P"
$PN"153"142;
"DQS10N"
$PN"19"155;
"DQS10P"
$PN"18"156;
"DQS11N"
$PN"30"157;
"DQS11P"
$PN"29"158;
"DQS12N"
$PN"41"159;
"DQS12P"
$PN"40"160;
"DQS13N"
$PN"100"161;
"DQS13P"
$PN"99"162;
"DQS14N"
$PN"111"163;
"DQS14P"
$PN"110"164;
"DQS15N"
$PN"122"165;
"DQS15P"
$PN"121"166;
"DQS16N"
$PN"133"167;
"DQS16P"
$PN"132"168;
"DQS17N"
$PN"52"169;
"DQS17P"
$PN"51"176;
"DQS1N"
$PN"163"143;
"DQS1P"
$PN"164"144;
"DQS2N"
$PN"174"145;
"DQS2P"
$PN"175"146;
"DQS3N"
$PN"185"147;
"DQS3P"
$PN"186"148;
"DQS4N"
$PN"244"149;
"DQS4P"
$PN"245"150;
"DQS5N"
$PN"255"151;
"DQS5P"
$PN"256"152;
"DQS6N"
$PN"266"153;
"DQS6P"
$PN"267"154;
"DQS7N"
$PN"277"170;
"DQS7P"
$PN"278"171;
"DQS8N"
$PN"196"172;
"DQS8P"
$PN"197"173;
"DQS9N"
$PN"8"174;
"DQS9P"
$PN"7"175;
%"TAP"
"6","(-1700,2500)","2","mstr_standard","I88";
;
HDL_TAP"TRUE"
BODY_TYPE"PLUMBING"
CDS_LIB"mstr_standard";
"B \NAC \NWC"4;
"S \NAC"
BN"18"73;
%"TAP"
"6","(-1700,2700)","2","mstr_standard","I89";
;
HDL_TAP"TRUE"
BODY_TYPE"PLUMBING"
CDS_LIB"mstr_standard";
"B \NAC \NWC"4;
"S \NAC"
BN"22"92;
%"PVTT_KLM"
"1","(-1150,2700)","0","mstr_symbols","I9";
;
HDL_POWER"PVTT_KLM"
ROOM"PROC"
BODY_TYPE"PLUMBING"
CDS_LIB"mstr_symbols"
BOM_COST"PROC"
VOLTAGE"0.6V";
"G\NAC"21;
%"TAP"
"6","(-1700,2650)","2","mstr_standard","I90";
;
HDL_TAP"TRUE"
BODY_TYPE"PLUMBING"
CDS_LIB"mstr_standard";
"B \NAC \NWC"4;
"S \NAC"
BN"21"88;
%"TAP"
"6","(-1700,2550)","2","mstr_standard","I91";
;
HDL_TAP"TRUE"
BODY_TYPE"PLUMBING"
CDS_LIB"mstr_standard";
"B \NAC \NWC"4;
"S \NAC"
BN"19"72;
%"TAP"
"6","(-1700,2600)","2","mstr_standard","I92";
;
HDL_TAP"TRUE"
BODY_TYPE"PLUMBING"
CDS_LIB"mstr_standard";
"B \NAC \NWC"4;
"S \NAC"
BN"20"89;
%"TAP"
"6","(-1700,2250)","2","mstr_standard","I93";
;
HDL_TAP"TRUE"
BODY_TYPE"PLUMBING"
CDS_LIB"mstr_standard";
"B \NAC \NWC"4;
"S \NAC"
BN"13"74;
%"TAP"
"6","(-1700,2400)","2","mstr_standard","I94";
;
HDL_TAP"TRUE"
BODY_TYPE"PLUMBING"
CDS_LIB"mstr_standard";
"B \NAC \NWC"4;
"S \NAC"
BN"16"82;
%"TAP"
"6","(-1700,2450)","2","mstr_standard","I95";
;
HDL_TAP"TRUE"
BODY_TYPE"PLUMBING"
CDS_LIB"mstr_standard";
"B \NAC \NWC"4;
"S \NAC"
BN"17"76;
%"TAP"
"6","(-1700,2300)","2","mstr_standard","I96";
;
HDL_TAP"TRUE"
BODY_TYPE"PLUMBING"
CDS_LIB"mstr_standard";
"B \NAC \NWC"4;
"S \NAC"
BN"14"80;
%"TAP"
"6","(-1700,2350)","2","mstr_standard","I97";
;
HDL_TAP"TRUE"
BODY_TYPE"PLUMBING"
CDS_LIB"mstr_standard";
"B \NAC \NWC"4;
"S \NAC"
BN"15"81;
%"TAP"
"6","(-1700,2000)","2","mstr_standard","I98";
;
HDL_TAP"TRUE"
BODY_TYPE"PLUMBING"
CDS_LIB"mstr_standard";
"B \NAC \NWC"4;
"S \NAC"
BN"8"71;
%"TAP"
"6","(-1700,2100)","2","mstr_standard","I99";
;
HDL_TAP"TRUE"
BODY_TYPE"PLUMBING"
CDS_LIB"mstr_standard";
"B \NAC \NWC"4;
"S \NAC"
BN"10"77;
END.
